(kicad_pcb
	(version 20260206)
	(generator "pcbnew")
	(generator_version "10.0")
	(general
		(thickness 1.6)
		(legacy_teardrops no)
	)
	(paper "A4")
	(title_block
		(title "baseboard — 13948-1b.1110WZS1818.brd")
		(comment 1 "Honey Badger (Wiwynn) / footprints 340-346 of 2523")
	)
	(layers
		(0 "F.Cu" signal "TOP")
		(4 "In1.Cu" signal "L2GND")
		(6 "In2.Cu" signal "L3")
		(8 "In3.Cu" signal "L4VCC")
		(10 "In4.Cu" signal "L5VCC")
		(12 "In5.Cu" signal "L6")
		(14 "In6.Cu" signal "L7GND")
		(2 "B.Cu" signal "BOTTOM")
		(9 "F.Adhes" user "F.Adhesive")
		(11 "B.Adhes" user "B.Adhesive")
		(13 "F.Paste" user "Package Geometry/Pastemask Top")
		(15 "B.Paste" user "Package Geometry/Pastemask Bottom")
		(5 "F.SilkS" user "Ref Des/Silkscreen Top")
		(7 "B.SilkS" user "Ref Des/Silkscreen Bottom")
		(1 "F.Mask" user "Board Geometry/Soldermask Top")
		(3 "B.Mask" user "Board Geometry/Soldermask Bottom")
		(17 "Dwgs.User" user "User.Drawings")
		(19 "Cmts.User" user "User.Comments")
		(21 "Eco1.User" user "User.Eco1")
		(23 "Eco2.User" user "User.Eco2")
		(25 "Edge.Cuts" user "Board Geometry/Outline")
		(27 "Margin" user)
		(31 "F.CrtYd" user "Package Geometry/Place Bound Top")
		(29 "B.CrtYd" user "Package Geometry/Place Bound Bottom")
		(35 "F.Fab" user "Ref Des/Assembly Top")
		(33 "B.Fab" user "Ref Des/Assembly Bottom")
	)
	(footprint ""
		(layer "F.Cu")
		(at 348.390718 -155.298648 -90)
		(property "Reference" "R533"
			(at 0 0 270)
			(layer "F.SilkS")
			(hide yes)
			(effects
				(font
					(size 1.27 1.27)
				)
			)
		)
		(property "Value" "0R2J-2-GP"
			(at 0.064008 -3.993896 270)
			(unlocked yes)
			(layer "F.Fab")
			(hide yes)
			(effects
				(font
					(size 1.016 1.016)
					(thickness 0.1524)
				)
			)
		)
		(property "Device Type" "R402H16"
			(at 0.064008 -5.517896 270)
			(unlocked yes)
			(layer "F.Fab")
			(hide yes)
			(effects
				(font
					(size 1.016 1.016)
					(thickness 0.1524)
				)
			)
		)
		(duplicate_pad_numbers_are_jumpers no)
		(fp_line
			(start -0.508 -0.9398)
			(end -0.508 0.9398)
			(stroke
				(width 0.1524)
				(type default)
			)
			(layer "F.SilkS")
		)
		(fp_line
			(start 0.508 -0.9398)
			(end -0.508 -0.9398)
			(stroke
				(width 0.1524)
				(type default)
			)
			(layer "F.SilkS")
		)
		(fp_rect
			(start -0.508 0.9398)
			(end 0.508 -0.9398)
			(stroke
				(width 0)
				(type default)
			)
			(fill no)
			(layer "F.CrtYd")
		)
		(fp_rect
			(start -0.508 0.9398)
			(end 0.508 -0.9398)
			(stroke
				(width 0)
				(type default)
			)
			(fill no)
			(layer "F.Fab")
		)
		(pad "1" smd custom
			(at 0 -0.4445 270)
			(size 0.1397 0.1397)
			(layers "F.Cu" "F.Mask" "F.Paste")
			(net "BMC_USB1_HDP2")
			(options
				(clearance outline)
				(anchor circle)
			)
			(primitives
				(gr_poly
					(pts
						(arc
							(start -0.1778 -0.2794)
							(mid -0.249642 -0.249642)
							(end -0.2794 -0.1778)
						)
						(arc
							(start -0.2794 0.1778)
							(mid -0.249642 0.249642)
							(end -0.1778 0.2794)
						)
						(arc
							(start 0.1778 0.2794)
							(mid 0.249642 0.249642)
							(end 0.2794 0.1778)
						)
						(arc
							(start 0.2794 -0.1778)
							(mid 0.249642 -0.249642)
							(end 0.1778 -0.2794)
						)
					)
					(width 0)
					(fill yes)
				)
			)
		)
		(pad "2" smd custom
			(at 0 0.4445 270)
			(size 0.1397 0.1397)
			(layers "F.Cu" "F.Mask" "F.Paste")
			(net "USB_P4_DP")
			(options
				(clearance outline)
				(anchor circle)
			)
			(primitives
				(gr_poly
					(pts
						(arc
							(start -0.1778 -0.2794)
							(mid -0.249642 -0.249642)
							(end -0.2794 -0.1778)
						)
						(arc
							(start -0.2794 0.1778)
							(mid -0.249642 0.249642)
							(end -0.1778 0.2794)
						)
						(arc
							(start 0.1778 0.2794)
							(mid 0.249642 0.249642)
							(end 0.2794 0.1778)
						)
						(arc
							(start 0.2794 -0.1778)
							(mid 0.249642 -0.249642)
							(end 0.1778 -0.2794)
						)
					)
					(width 0)
					(fill yes)
				)
			)
		)
	)
	(footprint ""
		(layer "F.Cu")
		(at 117.964966 -42.037 -90)
		(property "Reference" "SR666"
			(at 0 0 270)
			(layer "F.SilkS")
			(hide yes)
			(effects
				(font
					(size 1.27 1.27)
				)
			)
		)
		(property "Value" "10KR2F-2-GP"
			(at 0.064008 -3.993896 270)
			(unlocked yes)
			(layer "F.Fab")
			(hide yes)
			(effects
				(font
					(size 1.016 1.016)
					(thickness 0.1524)
				)
			)
		)
		(property "Device Type" "R402H16"
			(at 0.064008 -5.517896 270)
			(unlocked yes)
			(layer "F.Fab")
			(hide yes)
			(effects
				(font
					(size 1.016 1.016)
					(thickness 0.1524)
				)
			)
		)
		(duplicate_pad_numbers_are_jumpers no)
		(fp_line
			(start -0.508 -0.9398)
			(end -0.508 0.9398)
			(stroke
				(width 0.1524)
				(type default)
			)
			(layer "F.SilkS")
		)
		(fp_line
			(start 0.508 -0.9398)
			(end -0.508 -0.9398)
			(stroke
				(width 0.1524)
				(type default)
			)
			(layer "F.SilkS")
		)
		(fp_rect
			(start -0.508 0.9398)
			(end 0.508 -0.9398)
			(stroke
				(width 0)
				(type default)
			)
			(fill no)
			(layer "F.CrtYd")
		)
		(fp_rect
			(start -0.508 0.9398)
			(end 0.508 -0.9398)
			(stroke
				(width 0)
				(type default)
			)
			(fill no)
			(layer "F.Fab")
		)
		(pad "1" smd custom
			(at 0 -0.4445 270)
			(size 0.1397 0.1397)
			(layers "F.Cu" "F.Mask" "F.Paste")
			(net "P1V8_C")
			(options
				(clearance outline)
				(anchor circle)
			)
			(primitives
				(gr_poly
					(pts
						(arc
							(start -0.1778 -0.2794)
							(mid -0.249642 -0.249642)
							(end -0.2794 -0.1778)
						)
						(arc
							(start -0.2794 0.1778)
							(mid -0.249642 0.249642)
							(end -0.1778 0.2794)
						)
						(arc
							(start 0.1778 0.2794)
							(mid 0.249642 0.249642)
							(end 0.2794 0.1778)
						)
						(arc
							(start 0.2794 -0.1778)
							(mid 0.249642 -0.249642)
							(end 0.1778 -0.2794)
						)
					)
					(width 0)
					(fill yes)
				)
			)
		)
		(pad "2" smd custom
			(at 0 0.4445 270)
			(size 0.1397 0.1397)
			(layers "F.Cu" "F.Mask" "F.Paste")
			(net "CP_DONE")
			(options
				(clearance outline)
				(anchor circle)
			)
			(primitives
				(gr_poly
					(pts
						(arc
							(start -0.1778 -0.2794)
							(mid -0.249642 -0.249642)
							(end -0.2794 -0.1778)
						)
						(arc
							(start -0.2794 0.1778)
							(mid -0.249642 0.249642)
							(end -0.1778 0.2794)
						)
						(arc
							(start 0.1778 0.2794)
							(mid 0.249642 0.249642)
							(end 0.2794 0.1778)
						)
						(arc
							(start 0.2794 -0.1778)
							(mid 0.249642 -0.249642)
							(end 0.1778 -0.2794)
						)
					)
					(width 0)
					(fill yes)
				)
			)
		)
	)
	(footprint ""
		(layer "F.Cu")
		(at 66.715386 -108.122212 -90)
		(property "Reference" "PR169"
			(at 0 0 270)
			(layer "F.SilkS")
			(hide yes)
			(effects
				(font
					(size 1.27 1.27)
				)
			)
		)
		(property "Value" "0R2J-2-GP"
			(at 0.064008 -3.993896 270)
			(unlocked yes)
			(layer "F.Fab")
			(hide yes)
			(effects
				(font
					(size 1.016 1.016)
					(thickness 0.1524)
				)
			)
		)
		(property "Device Type" "R402H16"
			(at 0.064008 -5.517896 270)
			(unlocked yes)
			(layer "F.Fab")
			(hide yes)
			(effects
				(font
					(size 1.016 1.016)
					(thickness 0.1524)
				)
			)
		)
		(duplicate_pad_numbers_are_jumpers no)
		(fp_line
			(start -0.508 -0.9398)
			(end -0.508 0.9398)
			(stroke
				(width 0.1524)
				(type default)
			)
			(layer "F.SilkS")
		)
		(fp_line
			(start 0.508 -0.9398)
			(end -0.508 -0.9398)
			(stroke
				(width 0.1524)
				(type default)
			)
			(layer "F.SilkS")
		)
		(fp_rect
			(start -0.508 0.9398)
			(end 0.508 -0.9398)
			(stroke
				(width 0)
				(type default)
			)
			(fill no)
			(layer "F.CrtYd")
		)
		(fp_rect
			(start -0.508 0.9398)
			(end 0.508 -0.9398)
			(stroke
				(width 0)
				(type default)
			)
			(fill no)
			(layer "F.Fab")
		)
		(pad "1" smd custom
			(at 0 -0.4445 270)
			(size 0.1397 0.1397)
			(layers "F.Cu" "F.Mask" "F.Paste")
			(net "P1V8_EN_S")
			(options
				(clearance outline)
				(anchor circle)
			)
			(primitives
				(gr_poly
					(pts
						(arc
							(start -0.1778 -0.2794)
							(mid -0.249642 -0.249642)
							(end -0.2794 -0.1778)
						)
						(arc
							(start -0.2794 0.1778)
							(mid -0.249642 0.249642)
							(end -0.1778 0.2794)
						)
						(arc
							(start 0.1778 0.2794)
							(mid 0.249642 0.249642)
							(end 0.2794 0.1778)
						)
						(arc
							(start 0.2794 -0.1778)
							(mid 0.249642 -0.249642)
							(end 0.1778 -0.2794)
						)
					)
					(width 0)
					(fill yes)
				)
			)
		)
		(pad "2" smd custom
			(at 0 0.4445 270)
			(size 0.1397 0.1397)
			(layers "F.Cu" "F.Mask" "F.Paste")
			(net "P1V26_STBY_PG")
			(options
				(clearance outline)
				(anchor circle)
			)
			(primitives
				(gr_poly
					(pts
						(arc
							(start -0.1778 -0.2794)
							(mid -0.249642 -0.249642)
							(end -0.2794 -0.1778)
						)
						(arc
							(start -0.2794 0.1778)
							(mid -0.249642 0.249642)
							(end -0.1778 0.2794)
						)
						(arc
							(start 0.1778 0.2794)
							(mid 0.249642 0.249642)
							(end 0.2794 0.1778)
						)
						(arc
							(start 0.2794 -0.1778)
							(mid 0.249642 -0.249642)
							(end 0.1778 -0.2794)
						)
					)
					(width 0)
					(fill yes)
				)
			)
		)
	)
	(footprint ""
		(layer "F.Cu")
		(at 166.624 -154.1526 90)
		(property "Reference" "SR730"
			(at 0 0 90)
			(layer "F.SilkS")
			(hide yes)
			(effects
				(font
					(size 1.27 1.27)
				)
			)
		)
		(property "Value" "0R2J-2-GP"
			(at 0.064008 -3.993896 90)
			(unlocked yes)
			(layer "F.Fab")
			(hide yes)
			(effects
				(font
					(size 1.016 1.016)
					(thickness 0.1524)
				)
			)
		)
		(property "Device Type" "R402H16"
			(at 0.064008 -5.517896 90)
			(unlocked yes)
			(layer "F.Fab")
			(hide yes)
			(effects
				(font
					(size 1.016 1.016)
					(thickness 0.1524)
				)
			)
		)
		(duplicate_pad_numbers_are_jumpers no)
		(fp_line
			(start 0.508 -0.9398)
			(end -0.508 -0.9398)
			(stroke
				(width 0.1524)
				(type default)
			)
			(layer "F.SilkS")
		)
		(fp_line
			(start -0.508 -0.9398)
			(end -0.508 0.9398)
			(stroke
				(width 0.1524)
				(type default)
			)
			(layer "F.SilkS")
		)
		(fp_rect
			(start -0.508 0.9398)
			(end 0.508 -0.9398)
			(stroke
				(width 0)
				(type default)
			)
			(fill no)
			(layer "F.CrtYd")
		)
		(fp_rect
			(start -0.508 0.9398)
			(end 0.508 -0.9398)
			(stroke
				(width 0)
				(type default)
			)
			(fill no)
			(layer "F.Fab")
		)
		(pad "1" smd custom
			(at 0 -0.4445 90)
			(size 0.1397 0.1397)
			(layers "F.Cu" "F.Mask" "F.Paste")
			(net "IOC_P3V3_R_SDA_14")
			(options
				(clearance outline)
				(anchor circle)
			)
			(primitives
				(gr_poly
					(pts
						(arc
							(start -0.1778 -0.2794)
							(mid -0.249642 -0.249642)
							(end -0.2794 -0.1778)
						)
						(arc
							(start -0.2794 0.1778)
							(mid -0.249642 0.249642)
							(end -0.1778 0.2794)
						)
						(arc
							(start 0.1778 0.2794)
							(mid 0.249642 0.249642)
							(end 0.2794 0.1778)
						)
						(arc
							(start 0.2794 -0.1778)
							(mid 0.249642 -0.249642)
							(end 0.1778 -0.2794)
						)
					)
					(width 0)
					(fill yes)
				)
			)
		)
		(pad "2" smd custom
			(at 0 0.4445 90)
			(size 0.1397 0.1397)
			(layers "F.Cu" "F.Mask" "F.Paste")
			(net "IOC_P3V3_SDA_14")
			(options
				(clearance outline)
				(anchor circle)
			)
			(primitives
				(gr_poly
					(pts
						(arc
							(start -0.1778 -0.2794)
							(mid -0.249642 -0.249642)
							(end -0.2794 -0.1778)
						)
						(arc
							(start -0.2794 0.1778)
							(mid -0.249642 0.249642)
							(end -0.1778 0.2794)
						)
						(arc
							(start 0.1778 0.2794)
							(mid 0.249642 0.249642)
							(end 0.2794 0.1778)
						)
						(arc
							(start 0.2794 -0.1778)
							(mid 0.249642 -0.249642)
							(end 0.1778 -0.2794)
						)
					)
					(width 0)
					(fill yes)
				)
			)
		)
	)
	(footprint ""
		(layer "F.Cu")
		(at 108.966 -240.157 90)
		(property "Reference" "SR949"
			(at 0 0 90)
			(layer "F.SilkS")
			(hide yes)
			(effects
				(font
					(size 1.27 1.27)
				)
			)
		)
		(property "Value" "4K7R2F-GP"
			(at 0.064008 -3.993896 90)
			(unlocked yes)
			(layer "F.Fab")
			(hide yes)
			(effects
				(font
					(size 1.016 1.016)
					(thickness 0.1524)
				)
			)
		)
		(property "Device Type" "R402H16"
			(at 0.064008 -5.517896 90)
			(unlocked yes)
			(layer "F.Fab")
			(hide yes)
			(effects
				(font
					(size 1.016 1.016)
					(thickness 0.1524)
				)
			)
		)
		(duplicate_pad_numbers_are_jumpers no)
		(fp_line
			(start 0.508 -0.9398)
			(end -0.508 -0.9398)
			(stroke
				(width 0.1524)
				(type default)
			)
			(layer "F.SilkS")
		)
		(fp_line
			(start -0.508 -0.9398)
			(end -0.508 0.9398)
			(stroke
				(width 0.1524)
				(type default)
			)
			(layer "F.SilkS")
		)
		(fp_rect
			(start -0.508 0.9398)
			(end 0.508 -0.9398)
			(stroke
				(width 0)
				(type default)
			)
			(fill no)
			(layer "F.CrtYd")
		)
		(fp_rect
			(start -0.508 0.9398)
			(end 0.508 -0.9398)
			(stroke
				(width 0)
				(type default)
			)
			(fill no)
			(layer "F.Fab")
		)
		(pad "1" smd custom
			(at 0 -0.4445 90)
			(size 0.1397 0.1397)
			(layers "F.Cu" "F.Mask" "F.Paste")
			(net "SAS_FAULT_LED8")
			(options
				(clearance outline)
				(anchor circle)
			)
			(primitives
				(gr_poly
					(pts
						(arc
							(start -0.1778 -0.2794)
							(mid -0.249642 -0.249642)
							(end -0.2794 -0.1778)
						)
						(arc
							(start -0.2794 0.1778)
							(mid -0.249642 0.249642)
							(end -0.1778 0.2794)
						)
						(arc
							(start 0.1778 0.2794)
							(mid 0.249642 0.249642)
							(end 0.2794 0.1778)
						)
						(arc
							(start 0.2794 -0.1778)
							(mid 0.249642 -0.249642)
							(end 0.1778 -0.2794)
						)
					)
					(width 0)
					(fill yes)
				)
			)
		)
		(pad "2" smd custom
			(at 0 0.4445 90)
			(size 0.1397 0.1397)
			(layers "F.Cu" "F.Mask" "F.Paste")
			(net "P3V3_STBY")
			(options
				(clearance outline)
				(anchor circle)
			)
			(primitives
				(gr_poly
					(pts
						(arc
							(start -0.1778 -0.2794)
							(mid -0.249642 -0.249642)
							(end -0.2794 -0.1778)
						)
						(arc
							(start -0.2794 0.1778)
							(mid -0.249642 0.249642)
							(end -0.1778 0.2794)
						)
						(arc
							(start 0.1778 0.2794)
							(mid 0.249642 0.249642)
							(end 0.2794 0.1778)
						)
						(arc
							(start 0.2794 -0.1778)
							(mid 0.249642 -0.249642)
							(end 0.1778 -0.2794)
						)
					)
					(width 0)
					(fill yes)
				)
			)
		)
	)
	(footprint ""
		(layer "F.Cu")
		(at 291.973 -208.915 90)
		(property "Reference" "C179"
			(at 0 0 90)
			(layer "F.SilkS")
			(hide yes)
			(effects
				(font
					(size 1.27 1.27)
				)
			)
		)
		(property "Value" "SCD01U25V2KX-3GP"
			(at 1.1811 -2.7051 90)
			(unlocked yes)
			(layer "F.Fab")
			(hide yes)
			(effects
				(font
					(size 1.016 1.016)
					(thickness 0.1524)
				)
			)
		)
		(property "Device Type" "C402H22"
			(at 1.1811 -4.2291 90)
			(unlocked yes)
			(layer "F.Fab")
			(hide yes)
			(effects
				(font
					(size 1.016 1.016)
					(thickness 0.1524)
				)
			)
		)
		(duplicate_pad_numbers_are_jumpers no)
		(fp_rect
			(start -0.4318 0.9525)
			(end 0.4318 -0.9525)
			(stroke
				(width 0)
				(type default)
			)
			(fill no)
			(layer "F.CrtYd")
		)
		(fp_rect
			(start -0.4318 0.9525)
			(end 0.4318 -0.9525)
			(stroke
				(width 0)
				(type default)
			)
			(fill no)
			(layer "F.Fab")
		)
		(pad "1" smd custom
			(at 0 -0.4445 90)
			(size 0.1524 0.1524)
			(layers "F.Cu" "F.Mask" "F.Paste")
			(net "DDR_VREF")
			(options
				(clearance outline)
				(anchor circle)
			)
			(primitives
				(gr_poly
					(pts
						(arc
							(start 0.3048 -0.2032)
							(mid 0.275042 -0.275042)
							(end 0.2032 -0.3048)
						)
						(arc
							(start -0.2032 -0.3048)
							(mid -0.275042 -0.275042)
							(end -0.3048 -0.2032)
						)
						(arc
							(start -0.3048 0.2032)
							(mid -0.275042 0.275042)
							(end -0.2032 0.3048)
						)
						(arc
							(start 0.2032 0.3048)
							(mid 0.275042 0.275042)
							(end 0.3048 0.2032)
						)
					)
					(width 0)
					(fill yes)
				)
			)
		)
		(pad "2" smd custom
			(at 0 0.4445 90)
			(size 0.1524 0.1524)
			(layers "F.Cu" "F.Mask" "F.Paste")
			(net "GND")
			(options
				(clearance outline)
				(anchor circle)
			)
			(primitives
				(gr_poly
					(pts
						(arc
							(start 0.3048 -0.2032)
							(mid 0.275042 -0.275042)
							(end 0.2032 -0.3048)
						)
						(arc
							(start -0.2032 -0.3048)
							(mid -0.275042 -0.275042)
							(end -0.3048 -0.2032)
						)
						(arc
							(start -0.3048 0.2032)
							(mid -0.275042 0.275042)
							(end -0.2032 0.3048)
						)
						(arc
							(start 0.2032 0.3048)
							(mid 0.275042 0.275042)
							(end 0.3048 0.2032)
						)
					)
					(width 0)
					(fill yes)
				)
			)
		)
	)
	(footprint ""
		(layer "F.Cu")
		(at 89.643966 -69.342 180)
		(property "Reference" "SC1000"
			(at 0 0 180)
			(layer "F.SilkS")
			(hide yes)
			(effects
				(font
					(size 1.27 1.27)
				)
			)
		)
		(property "Value" "SCD1U16V2KX-3GP"
			(at 1.1811 -2.7051 180)
			(unlocked yes)
			(layer "F.Fab")
			(hide yes)
			(effects
				(font
					(size 1.016 1.016)
					(thickness 0.1524)
				)
			)
		)
		(property "Device Type" "C402H22"
			(at 1.1811 -4.2291 180)
			(unlocked yes)
			(layer "F.Fab")
			(hide yes)
			(effects
				(font
					(size 1.016 1.016)
					(thickness 0.1524)
				)
			)
		)
		(duplicate_pad_numbers_are_jumpers no)
		(fp_rect
			(start -0.4318 0.9525)
			(end 0.4318 -0.9525)
			(stroke
				(width 0)
				(type default)
			)
			(fill no)
			(layer "F.CrtYd")
		)
		(fp_rect
			(start -0.4318 0.9525)
			(end 0.4318 -0.9525)
			(stroke
				(width 0)
				(type default)
			)
			(fill no)
			(layer "F.Fab")
		)
		(pad "1" smd custom
			(at 0 -0.4445 180)
			(size 0.1524 0.1524)
			(layers "F.Cu" "F.Mask" "F.Paste")
			(net "P1V8_C")
			(options
				(clearance outline)
				(anchor circle)
			)
			(primitives
				(gr_poly
					(pts
						(arc
							(start 0.3048 -0.2032)
							(mid 0.275042 -0.275042)
							(end 0.2032 -0.3048)
						)
						(arc
							(start -0.2032 -0.3048)
							(mid -0.275042 -0.275042)
							(end -0.3048 -0.2032)
						)
						(arc
							(start -0.3048 0.2032)
							(mid -0.275042 0.275042)
							(end -0.2032 0.3048)
						)
						(arc
							(start 0.2032 0.3048)
							(mid 0.275042 0.275042)
							(end 0.3048 0.2032)
						)
					)
					(width 0)
					(fill yes)
				)
			)
		)
		(pad "2" smd custom
			(at 0 0.4445 180)
			(size 0.1524 0.1524)
			(layers "F.Cu" "F.Mask" "F.Paste")
			(net "GND")
			(options
				(clearance outline)
				(anchor circle)
			)
			(primitives
				(gr_poly
					(pts
						(arc
							(start 0.3048 -0.2032)
							(mid 0.275042 -0.275042)
							(end 0.2032 -0.3048)
						)
						(arc
							(start -0.2032 -0.3048)
							(mid -0.275042 -0.275042)
							(end -0.3048 -0.2032)
						)
						(arc
							(start -0.3048 0.2032)
							(mid -0.275042 0.275042)
							(end -0.2032 0.3048)
						)
						(arc
							(start 0.2032 0.3048)
							(mid 0.275042 0.275042)
							(end 0.3048 0.2032)
						)
					)
					(width 0)
					(fill yes)
				)
			)
		)
	)
)
